(kicad_pcb
	(version 20260206)
	(generator "pcbnew")
	(generator_version "10.0")
	(general
		(thickness 1.6)
		(legacy_teardrops no)
	)
	(paper "A4")
	(title_block
		(title "04192023_DAF0TMB3IC0_F0TG_MB_C_brd_V02_OCP.brd")
		(comment 1 "Grand Teton / footprints 7229-7235 of 8354")
	)
	(layers
		(0 "F.Cu" signal "TOP")
		(4 "In1.Cu" signal "GND")
		(6 "In2.Cu" signal "IN1")
		(8 "In3.Cu" signal "GND1")
		(10 "In4.Cu" signal "IN2")
		(12 "In5.Cu" signal "GND2")
		(14 "In6.Cu" signal "IN3")
		(16 "In7.Cu" signal "GND3")
		(18 "In8.Cu" signal "VCC")
		(20 "In9.Cu" signal "VCC1")
		(22 "In10.Cu" signal "GND4")
		(24 "In11.Cu" signal "IN4")
		(26 "In12.Cu" signal "GND5")
		(28 "In13.Cu" signal "IN5")
		(30 "In14.Cu" signal "GND6")
		(32 "In15.Cu" signal "IN6")
		(34 "In16.Cu" signal "GND7")
		(2 "B.Cu" signal "BOTTOM")
		(9 "F.Adhes" user "F.Adhesive")
		(11 "B.Adhes" user "B.Adhesive")
		(13 "F.Paste" user "Package Geometry/Pastemask Top")
		(15 "B.Paste" user "Package Geometry/Pastemask Bottom")
		(5 "F.SilkS" user "Ref Des/Silkscreen Top")
		(7 "B.SilkS" user "Ref Des/Silkscreen Bottom")
		(1 "F.Mask" user "Board Geometry/Soldermask Top")
		(3 "B.Mask" user "Board Geometry/Soldermask Bottom")
		(17 "Dwgs.User" user "User.Drawings")
		(19 "Cmts.User" user "User.Comments")
		(21 "Eco1.User" user "User.Eco1")
		(23 "Eco2.User" user "User.Eco2")
		(25 "Edge.Cuts" user "Board Geometry/Outline")
		(27 "Margin" user)
		(31 "F.CrtYd" user "Package Geometry/Place Bound Top")
		(29 "B.CrtYd" user "Package Geometry/Place Bound Bottom")
		(35 "F.Fab" user "Ref Des/Assembly Top")
		(33 "B.Fab" user "Ref Des/Assembly Bottom")
	)
	(footprint ""
		(layer "B.Cu")
		(at 111.781336 -253.432564 180)
		(property "Reference" "C2272"
			(at 0 0 0)
			(layer "B.SilkS")
			(hide yes)
			(effects
				(font
					(size 1.27 1.27)
				)
				(justify mirror)
			)
		)
		(property "Value" ""
			(at 0 0 0)
			(layer "B.Fab")
			(effects
				(font
					(size 1.27 1.27)
				)
				(justify mirror)
			)
		)
		(duplicate_pad_numbers_are_jumpers no)
		(fp_line
			(start 0.7874 0.4064)
			(end 0.7874 -0.4064)
			(stroke
				(width 0.1524)
				(type default)
			)
			(layer "B.SilkS")
		)
		(fp_line
			(start 0.7874 -0.4064)
			(end -0.7874 -0.4064)
			(stroke
				(width 0.1524)
				(type default)
			)
			(layer "B.SilkS")
		)
		(fp_line
			(start -0.7874 0.4064)
			(end 0.7874 0.4064)
			(stroke
				(width 0.1524)
				(type default)
			)
			(layer "B.SilkS")
		)
		(fp_line
			(start -0.7874 -0.4064)
			(end -0.7874 0.4064)
			(stroke
				(width 0.1524)
				(type default)
			)
			(layer "B.SilkS")
		)
		(fp_line
			(start 0.67945 0.3048)
			(end 0.67945 -0.305054)
			(stroke
				(width 0.1)
				(type default)
			)
			(layer "B.Fab")
		)
		(fp_line
			(start 0.67945 -0.305054)
			(end 0.12065 -0.305054)
			(stroke
				(width 0.1)
				(type default)
			)
			(layer "B.Fab")
		)
		(fp_line
			(start 0.12065 0.3048)
			(end 0.67945 0.3048)
			(stroke
				(width 0.1)
				(type default)
			)
			(layer "B.Fab")
		)
		(fp_line
			(start 0.12065 0.2794)
			(end 0.12065 0.3048)
			(stroke
				(width 0.1)
				(type default)
			)
			(layer "B.Fab")
		)
		(fp_line
			(start 0.12065 -0.2794)
			(end -0.12065 -0.2794)
			(stroke
				(width 0.1)
				(type default)
			)
			(layer "B.Fab")
		)
		(fp_line
			(start 0.12065 -0.305054)
			(end 0.12065 -0.2794)
			(stroke
				(width 0.1)
				(type default)
			)
			(layer "B.Fab")
		)
		(fp_line
			(start -0.120396 0.3048)
			(end -0.120396 0.2794)
			(stroke
				(width 0.1)
				(type default)
			)
			(layer "B.Fab")
		)
		(fp_line
			(start -0.120396 0.2794)
			(end 0.12065 0.2794)
			(stroke
				(width 0.1)
				(type default)
			)
			(layer "B.Fab")
		)
		(fp_line
			(start -0.12065 -0.2794)
			(end -0.12065 -0.3048)
			(stroke
				(width 0.1)
				(type default)
			)
			(layer "B.Fab")
		)
		(fp_line
			(start -0.12065 -0.3048)
			(end -0.67945 -0.3048)
			(stroke
				(width 0.1)
				(type default)
			)
			(layer "B.Fab")
		)
		(fp_line
			(start -0.67945 0.3048)
			(end -0.120396 0.3048)
			(stroke
				(width 0.1)
				(type default)
			)
			(layer "B.Fab")
		)
		(fp_line
			(start -0.67945 -0.3048)
			(end -0.67945 0.3048)
			(stroke
				(width 0.1)
				(type default)
			)
			(layer "B.Fab")
		)
		(pad "1" smd circle
			(at 0.40005 0)
			(size 0 0)
			(layers "B.Cu" "B.Mask" "B.Paste")
			(net "PVDDCR_SOC_P1")
		)
		(pad "2" smd circle
			(at -0.40005 0)
			(size 0 0)
			(layers "B.Cu" "B.Mask" "B.Paste")
			(net "GND")
		)
	)
	(footprint ""
		(layer "B.Cu")
		(at 105.960164 -259.355336 180)
		(property "Reference" "C3910"
			(at 0 0 0)
			(layer "B.SilkS")
			(hide yes)
			(effects
				(font
					(size 1.27 1.27)
				)
				(justify mirror)
			)
		)
		(property "Value" ""
			(at 0 0 0)
			(layer "B.Fab")
			(effects
				(font
					(size 1.27 1.27)
				)
				(justify mirror)
			)
		)
		(duplicate_pad_numbers_are_jumpers no)
		(fp_line
			(start 0.7874 0.4064)
			(end 0.7874 -0.4064)
			(stroke
				(width 0.1524)
				(type default)
			)
			(layer "B.SilkS")
		)
		(fp_line
			(start 0.7874 -0.4064)
			(end -0.7874 -0.4064)
			(stroke
				(width 0.1524)
				(type default)
			)
			(layer "B.SilkS")
		)
		(fp_line
			(start -0.7874 0.4064)
			(end 0.7874 0.4064)
			(stroke
				(width 0.1524)
				(type default)
			)
			(layer "B.SilkS")
		)
		(fp_line
			(start -0.7874 -0.4064)
			(end -0.7874 0.4064)
			(stroke
				(width 0.1524)
				(type default)
			)
			(layer "B.SilkS")
		)
		(fp_line
			(start 0.67945 0.3048)
			(end 0.67945 -0.305054)
			(stroke
				(width 0.1)
				(type default)
			)
			(layer "B.Fab")
		)
		(fp_line
			(start 0.67945 -0.305054)
			(end 0.12065 -0.305054)
			(stroke
				(width 0.1)
				(type default)
			)
			(layer "B.Fab")
		)
		(fp_line
			(start 0.12065 0.3048)
			(end 0.67945 0.3048)
			(stroke
				(width 0.1)
				(type default)
			)
			(layer "B.Fab")
		)
		(fp_line
			(start 0.12065 0.2794)
			(end 0.12065 0.3048)
			(stroke
				(width 0.1)
				(type default)
			)
			(layer "B.Fab")
		)
		(fp_line
			(start 0.12065 -0.2794)
			(end -0.12065 -0.2794)
			(stroke
				(width 0.1)
				(type default)
			)
			(layer "B.Fab")
		)
		(fp_line
			(start 0.12065 -0.305054)
			(end 0.12065 -0.2794)
			(stroke
				(width 0.1)
				(type default)
			)
			(layer "B.Fab")
		)
		(fp_line
			(start -0.120396 0.3048)
			(end -0.120396 0.2794)
			(stroke
				(width 0.1)
				(type default)
			)
			(layer "B.Fab")
		)
		(fp_line
			(start -0.120396 0.2794)
			(end 0.12065 0.2794)
			(stroke
				(width 0.1)
				(type default)
			)
			(layer "B.Fab")
		)
		(fp_line
			(start -0.12065 -0.2794)
			(end -0.12065 -0.3048)
			(stroke
				(width 0.1)
				(type default)
			)
			(layer "B.Fab")
		)
		(fp_line
			(start -0.12065 -0.3048)
			(end -0.67945 -0.3048)
			(stroke
				(width 0.1)
				(type default)
			)
			(layer "B.Fab")
		)
		(fp_line
			(start -0.67945 0.3048)
			(end -0.120396 0.3048)
			(stroke
				(width 0.1)
				(type default)
			)
			(layer "B.Fab")
		)
		(fp_line
			(start -0.67945 -0.3048)
			(end -0.67945 0.3048)
			(stroke
				(width 0.1)
				(type default)
			)
			(layer "B.Fab")
		)
		(pad "1" smd circle
			(at 0.40005 0)
			(size 0 0)
			(layers "B.Cu" "B.Mask" "B.Paste")
			(net "PVDDIO_P1")
		)
		(pad "2" smd circle
			(at -0.40005 0)
			(size 0 0)
			(layers "B.Cu" "B.Mask" "B.Paste")
			(net "GND")
		)
	)
	(footprint ""
		(layer "B.Cu")
		(at 25.152096 -192.66027 180)
		(property "Reference" "C509"
			(at 0 0 0)
			(layer "B.SilkS")
			(hide yes)
			(effects
				(font
					(size 1.27 1.27)
				)
				(justify mirror)
			)
		)
		(property "Value" ""
			(at 0 0 0)
			(layer "B.Fab")
			(effects
				(font
					(size 1.27 1.27)
				)
				(justify mirror)
			)
		)
		(duplicate_pad_numbers_are_jumpers no)
		(fp_line
			(start 1.524 0.762)
			(end 1.524 -0.762)
			(stroke
				(width 0.1524)
				(type default)
			)
			(layer "B.SilkS")
		)
		(fp_line
			(start 1.524 -0.762)
			(end -1.524 -0.762)
			(stroke
				(width 0.1524)
				(type default)
			)
			(layer "B.SilkS")
		)
		(fp_line
			(start -1.524 0.762)
			(end 1.524 0.762)
			(stroke
				(width 0.1524)
				(type default)
			)
			(layer "B.SilkS")
		)
		(fp_line
			(start -1.524 -0.762)
			(end -1.524 0.762)
			(stroke
				(width 0.1524)
				(type default)
			)
			(layer "B.SilkS")
		)
		(fp_line
			(start 1.1049 0.724916)
			(end -1.1049 0.724916)
			(stroke
				(width 0.1)
				(type default)
			)
			(layer "B.Fab")
		)
		(fp_line
			(start 1.1049 -0.724916)
			(end 1.1049 0.724916)
			(stroke
				(width 0.1)
				(type default)
			)
			(layer "B.Fab")
		)
		(fp_line
			(start -1.1049 0.724916)
			(end -1.1049 -0.724916)
			(stroke
				(width 0.1)
				(type default)
			)
			(layer "B.Fab")
		)
		(fp_line
			(start -1.1049 -0.724916)
			(end 1.1049 -0.724916)
			(stroke
				(width 0.1)
				(type default)
			)
			(layer "B.Fab")
		)
		(pad "1" smd rect
			(at 0.889 0 180)
			(size 1.016 1.27)
			(layers "B.Cu" "B.Mask" "B.Paste")
			(net "P12V_MEM_CPU1")
		)
		(pad "2" smd rect
			(at -0.889 0 180)
			(size 1.016 1.27)
			(layers "B.Cu" "B.Mask" "B.Paste")
			(net "GND")
		)
	)
	(footprint ""
		(layer "B.Cu")
		(at 41.162732 -337.989672 -90)
		(property "Reference" "PC637_3"
			(at 0 0 90)
			(layer "B.SilkS")
			(hide yes)
			(effects
				(font
					(size 1.27 1.27)
				)
				(justify mirror)
			)
		)
		(property "Value" ""
			(at 0 0 90)
			(layer "B.Fab")
			(effects
				(font
					(size 1.27 1.27)
				)
				(justify mirror)
			)
		)
		(duplicate_pad_numbers_are_jumpers no)
		(fp_line
			(start -1.524 0.762)
			(end 1.524 0.762)
			(stroke
				(width 0.1524)
				(type default)
			)
			(layer "B.SilkS")
		)
		(fp_line
			(start 1.524 0.762)
			(end 1.524 -0.762)
			(stroke
				(width 0.1524)
				(type default)
			)
			(layer "B.SilkS")
		)
		(fp_line
			(start -1.524 -0.762)
			(end -1.524 0.762)
			(stroke
				(width 0.1524)
				(type default)
			)
			(layer "B.SilkS")
		)
		(fp_line
			(start 1.524 -0.762)
			(end -1.524 -0.762)
			(stroke
				(width 0.1524)
				(type default)
			)
			(layer "B.SilkS")
		)
		(fp_line
			(start -1.1049 0.724916)
			(end -1.1049 -0.724916)
			(stroke
				(width 0.1)
				(type default)
			)
			(layer "B.Fab")
		)
		(fp_line
			(start 1.1049 0.724916)
			(end -1.1049 0.724916)
			(stroke
				(width 0.1)
				(type default)
			)
			(layer "B.Fab")
		)
		(fp_line
			(start -1.1049 -0.724916)
			(end 1.1049 -0.724916)
			(stroke
				(width 0.1)
				(type default)
			)
			(layer "B.Fab")
		)
		(fp_line
			(start 1.1049 -0.724916)
			(end 1.1049 0.724916)
			(stroke
				(width 0.1)
				(type default)
			)
			(layer "B.Fab")
		)
		(pad "1" smd rect
			(at 0.889 0 270)
			(size 1.016 1.27)
			(layers "B.Cu" "B.Mask" "B.Paste")
			(net "PVDDIO_P1")
		)
		(pad "2" smd rect
			(at -0.889 0 270)
			(size 1.016 1.27)
			(layers "B.Cu" "B.Mask" "B.Paste")
			(net "GND")
		)
	)
	(footprint ""
		(layer "B.Cu")
		(at 363.217206 -261.747762 90)
		(property "Reference" "C2137"
			(at 0 0 90)
			(layer "B.SilkS")
			(hide yes)
			(effects
				(font
					(size 1.27 1.27)
				)
				(justify mirror)
			)
		)
		(property "Value" ""
			(at 0 0 90)
			(layer "B.Fab")
			(effects
				(font
					(size 1.27 1.27)
				)
				(justify mirror)
			)
		)
		(duplicate_pad_numbers_are_jumpers no)
		(fp_line
			(start 0.7874 -0.4064)
			(end -0.7874 -0.4064)
			(stroke
				(width 0.1524)
				(type default)
			)
			(layer "B.SilkS")
		)
		(fp_line
			(start -0.7874 -0.4064)
			(end -0.7874 0.4064)
			(stroke
				(width 0.1524)
				(type default)
			)
			(layer "B.SilkS")
		)
		(fp_line
			(start 0.7874 0.4064)
			(end 0.7874 -0.4064)
			(stroke
				(width 0.1524)
				(type default)
			)
			(layer "B.SilkS")
		)
		(fp_line
			(start -0.7874 0.4064)
			(end 0.7874 0.4064)
			(stroke
				(width 0.1524)
				(type default)
			)
			(layer "B.SilkS")
		)
		(fp_line
			(start 0.67945 -0.305054)
			(end 0.12065 -0.305054)
			(stroke
				(width 0.1)
				(type default)
			)
			(layer "B.Fab")
		)
		(fp_line
			(start 0.12065 -0.305054)
			(end 0.12065 -0.2794)
			(stroke
				(width 0.1)
				(type default)
			)
			(layer "B.Fab")
		)
		(fp_line
			(start -0.12065 -0.3048)
			(end -0.67945 -0.3048)
			(stroke
				(width 0.1)
				(type default)
			)
			(layer "B.Fab")
		)
		(fp_line
			(start -0.67945 -0.3048)
			(end -0.67945 0.3048)
			(stroke
				(width 0.1)
				(type default)
			)
			(layer "B.Fab")
		)
		(fp_line
			(start 0.12065 -0.2794)
			(end -0.12065 -0.2794)
			(stroke
				(width 0.1)
				(type default)
			)
			(layer "B.Fab")
		)
		(fp_line
			(start -0.12065 -0.2794)
			(end -0.12065 -0.3048)
			(stroke
				(width 0.1)
				(type default)
			)
			(layer "B.Fab")
		)
		(fp_line
			(start 0.12065 0.2794)
			(end 0.12065 0.3048)
			(stroke
				(width 0.1)
				(type default)
			)
			(layer "B.Fab")
		)
		(fp_line
			(start -0.120396 0.2794)
			(end 0.12065 0.2794)
			(stroke
				(width 0.1)
				(type default)
			)
			(layer "B.Fab")
		)
		(fp_line
			(start 0.67945 0.3048)
			(end 0.67945 -0.305054)
			(stroke
				(width 0.1)
				(type default)
			)
			(layer "B.Fab")
		)
		(fp_line
			(start 0.12065 0.3048)
			(end 0.67945 0.3048)
			(stroke
				(width 0.1)
				(type default)
			)
			(layer "B.Fab")
		)
		(fp_line
			(start -0.120396 0.3048)
			(end -0.120396 0.2794)
			(stroke
				(width 0.1)
				(type default)
			)
			(layer "B.Fab")
		)
		(fp_line
			(start -0.67945 0.3048)
			(end -0.120396 0.3048)
			(stroke
				(width 0.1)
				(type default)
			)
			(layer "B.Fab")
		)
		(pad "1" smd circle
			(at 0.40005 0 270)
			(size 0 0)
			(layers "B.Cu" "B.Mask" "B.Paste")
			(net "PVDD11_S3_P0")
		)
		(pad "2" smd circle
			(at -0.40005 0 270)
			(size 0 0)
			(layers "B.Cu" "B.Mask" "B.Paste")
			(net "GND")
		)
	)
	(footprint ""
		(layer "B.Cu")
		(at 216.212674 -76.591668 180)
		(property "Reference" "R3211"
			(at 0 0 0)
			(layer "B.SilkS")
			(hide yes)
			(effects
				(font
					(size 1.27 1.27)
				)
				(justify mirror)
			)
		)
		(property "Value" ""
			(at 0 0 0)
			(layer "B.Fab")
			(effects
				(font
					(size 1.27 1.27)
				)
				(justify mirror)
			)
		)
		(duplicate_pad_numbers_are_jumpers no)
		(fp_line
			(start 0.7874 0.4064)
			(end 0.7874 -0.4064)
			(stroke
				(width 0.1524)
				(type default)
			)
			(layer "B.SilkS")
		)
		(fp_line
			(start 0.7874 -0.4064)
			(end -0.7874 -0.4064)
			(stroke
				(width 0.1524)
				(type default)
			)
			(layer "B.SilkS")
		)
		(fp_line
			(start -0.7874 0.4064)
			(end 0.7874 0.4064)
			(stroke
				(width 0.1524)
				(type default)
			)
			(layer "B.SilkS")
		)
		(fp_line
			(start -0.7874 -0.4064)
			(end -0.7874 0.4064)
			(stroke
				(width 0.1524)
				(type default)
			)
			(layer "B.SilkS")
		)
		(fp_line
			(start 0.67945 0.3048)
			(end 0.67945 -0.305054)
			(stroke
				(width 0.1)
				(type default)
			)
			(layer "B.Fab")
		)
		(fp_line
			(start 0.67945 -0.305054)
			(end 0.12065 -0.305054)
			(stroke
				(width 0.1)
				(type default)
			)
			(layer "B.Fab")
		)
		(fp_line
			(start 0.12065 0.3048)
			(end 0.67945 0.3048)
			(stroke
				(width 0.1)
				(type default)
			)
			(layer "B.Fab")
		)
		(fp_line
			(start 0.12065 0.2794)
			(end 0.12065 0.3048)
			(stroke
				(width 0.1)
				(type default)
			)
			(layer "B.Fab")
		)
		(fp_line
			(start 0.12065 -0.2794)
			(end -0.12065 -0.2794)
			(stroke
				(width 0.1)
				(type default)
			)
			(layer "B.Fab")
		)
		(fp_line
			(start 0.12065 -0.305054)
			(end 0.12065 -0.2794)
			(stroke
				(width 0.1)
				(type default)
			)
			(layer "B.Fab")
		)
		(fp_line
			(start -0.120396 0.3048)
			(end -0.120396 0.2794)
			(stroke
				(width 0.1)
				(type default)
			)
			(layer "B.Fab")
		)
		(fp_line
			(start -0.120396 0.2794)
			(end 0.12065 0.2794)
			(stroke
				(width 0.1)
				(type default)
			)
			(layer "B.Fab")
		)
		(fp_line
			(start -0.12065 -0.2794)
			(end -0.12065 -0.3048)
			(stroke
				(width 0.1)
				(type default)
			)
			(layer "B.Fab")
		)
		(fp_line
			(start -0.12065 -0.3048)
			(end -0.67945 -0.3048)
			(stroke
				(width 0.1)
				(type default)
			)
			(layer "B.Fab")
		)
		(fp_line
			(start -0.67945 0.3048)
			(end -0.120396 0.3048)
			(stroke
				(width 0.1)
				(type default)
			)
			(layer "B.Fab")
		)
		(fp_line
			(start -0.67945 -0.3048)
			(end -0.67945 0.3048)
			(stroke
				(width 0.1)
				(type default)
			)
			(layer "B.Fab")
		)
		(pad "1" smd circle
			(at 0.40005 0)
			(size 0 0)
			(layers "B.Cu" "B.Mask" "B.Paste")
			(net "NCSI_BMC_RXD0_R1")
		)
		(pad "2" smd circle
			(at -0.40005 0)
			(size 0 0)
			(layers "B.Cu" "B.Mask" "B.Paste")
			(net "RMII_OCP_BMC_RXD_0")
		)
	)
	(footprint ""
		(layer "B.Cu")
		(at 149.54631 -388.011162 -90)
		(property "Reference" "C411"
			(at 0 0 90)
			(layer "B.SilkS")
			(hide yes)
			(effects
				(font
					(size 1.27 1.27)
				)
				(justify mirror)
			)
		)
		(property "Value" ""
			(at 0 0 90)
			(layer "B.Fab")
			(effects
				(font
					(size 1.27 1.27)
				)
				(justify mirror)
			)
		)
		(duplicate_pad_numbers_are_jumpers no)
		(fp_line
			(start -0.299974 0.150114)
			(end 0.299974 0.150114)
			(stroke
				(width 0.1)
				(type default)
			)
			(layer "B.Fab")
		)
		(fp_line
			(start 0.299974 0.150114)
			(end 0.299974 -0.150114)
			(stroke
				(width 0.1)
				(type default)
			)
			(layer "B.Fab")
		)
		(fp_line
			(start -0.299974 -0.150114)
			(end -0.299974 0.150114)
			(stroke
				(width 0.1)
				(type default)
			)
			(layer "B.Fab")
		)
		(fp_line
			(start 0.299974 -0.150114)
			(end -0.299974 -0.150114)
			(stroke
				(width 0.1)
				(type default)
			)
			(layer "B.Fab")
		)
		(pad "1" smd rect
			(at 0.2667 0 90)
			(size 0.3048 0.381)
			(layers "B.Cu" "B.Mask" "B.Paste")
			(net "P0V9_CPU1_RT2_2A")
		)
		(pad "2" smd rect
			(at -0.2667 0 90)
			(size 0.3048 0.381)
			(layers "B.Cu" "B.Mask" "B.Paste")
			(net "GND")
		)
	)
)
